FILE_TYPE = CONNECTIVITY;
{Allegro Design Entry HDL 16.6-p007 (v16-6-112F) 10/10/2012}
"PAGE_NUMBER" = 136;
0"NC";
1"GND\g";
2"P3V3_STBY\g";
3"P3V3_STBY\g";
4"GND\g";
5"P3V3_STBY\g";
6"GND\g";
7"GND\g";
8"GND\g";
9"P3V3_STBY\g";
10"GND\g";
11"RST_PLTRST_N";
12"PU_BIOS_USB_RECOVERY";
13"PU_BIOS_RECOVER_BOOT";
14"FM_BIOS_TOP_SWAP";
15"FM_BIOS_USB_RECOVERY";
16"TP_BIOS_RECOVER_BOOT";
17"TP_BIOS_USB_RECOVERY";
18"FM_PASSWORD_CLEAR_N";
19"TP_ME_RCVR_BOOT";
20"TP_PASSWORD_CLEAR";
21"PD_ME_RCVR_N";
22"PD_PASSWORD_CLEAR";
23"FM_ME_RECOVER_N";
24"FM_BIOS_TOP_SWAP_SPKR_R";
25"FM_BIOS_TOP_SWAP_SPKR";
26"RST_PLTRST_TOP_SWAP";
27"FM_BIOS_TOP_SWAP";
%"RES"
"2","(-2250,4800)","0","mstr_discrete","I101";
;
CDS_SEC"1"
CDS_LOCATION"R7G26"
LOCATION"R7G26"
PART_NUMBER"G21796-016"
VALUE"10.0K"
TOLERANCE"1%"
PACK_TYPE"0402"
MATERIAL"CHIP"
WATTAGE"1/16W"
ROOM"SB"
CDS_LIB"mstr_discrete"
SEC_TYPE"0402"
SEC"1";
"A"
$PN"1"2;
"B"
$PN"2"23;
%"RES"
"2","(-2450,3825)","0","mstr_discrete","I102";
;
CDS_SEC"1"
CDS_LOCATION"R7G28"
PART_NUMBER"G21796-026"
MATERIAL"CHIP"
WATTAGE"1/16W"
VALUE"1.00K"
LOCATION"R7G28"
TOLERANCE"1%"
PACK_TYPE"0402"
ROOM"SB"
SEC"1"
SEC_TYPE"0402"
BOM_COST"SB"
CDS_LIB"mstr_discrete";
"A"
$PN"1"21;
"B"
$PN"2"1;
%"GND"
"1","(-2450,3625)","0","mstr_symbols","I103";
;
HDL_POWER"GND"
BODY_TYPE"PLUMBING"
VOLTAGE"0"
SIZE"1B"
BOM_COST"SB"
CDS_LIB"mstr_symbols";
"A\NAC"1;
%"P3V3_STBY"
"1","(-2250,5025)","0","mstr_symbols","I124";
;
HDL_POWER"P3V3_STBY"
BODY_TYPE"PLUMBING"
VOLTAGE"3.3V"
CDS_LIB"mstr_symbols"
SIZE"1B";
"G\NAC"2;
%"RES"
"1","(1000,2300)","0","mstr_discrete","I126";
;
CDS_SEC"1"
PART_NUMBER"G21796-074"
TOLERANCE"1%"
LOCATION"R8E20"
PACK_TYPE"0402"
MATERIAL"CHIP"
WATTAGE"1/16W"
VALUE"33.2"
ROOM"SB"
CDS_LOCATION"R8E20"
SEC"1"
BOM_COST"SB"
SEC_TYPE"0402"
CDS_LIB"mstr_discrete";
"B"
$PN"2"25;
"A"
$PN"1"24;
%"P3V3_STBY"
"1","(575,1825)","0","mstr_symbols","I127";
;
HDL_POWER"P3V3_STBY"
BODY_TYPE"PLUMBING"
VOLTAGE"3.3V"
CDS_LIB"mstr_symbols"
SIZE"1B";
"G\NAC"3;
%"CAP_A"
"1","(575,1575)","0","dev_discrete","I128";
;
LOCATION"C8E8"
PART_NUMBER"A36096-030"
VALUE"0.1UF"
TOLERANCE"10%"
PACK_TYPE"0402V"
VOLTAGE"16V"
MATERIAL"X7R"
ROOM"SB"
SEC"1"
SEC_TYPE"0402V"
CDS_SEC"1"
CDS_LIB"dev_discrete"
BOM_COST"SB"
CDS_LOCATION"C8E8";
"B"
$PN"2"4;
"A"
$PN"1"3;
%"GND"
"1","(575,1300)","0","mstr_symbols","I129";
;
HDL_POWER"GND"
BODY_TYPE"PLUMBING"
VOLTAGE"0.0V"
CDS_LIB"mstr_symbols"
SIZE"1B";
"A\NAC"4;
%"TTL1G126_A"
"1","(0,2300)","0","mstr_ttl","I130";
;
CDS_SEC"1"
PART_NUMBER"A79322-001"
POWER_GROUP"VCC=P3V3_STBY;GND=GND;"
LOCATION"U8E3"
VALUE"74HC1G126"
MATERIAL"IC"
PACK_TYPE"SOT"
ROOM"SB"
CDS_LOCATION"U8E3"
SEC"1"
CDS_LIB"mstr_ttl"
SEC_TYPE"SOT"
BOM_COST"SB";
"OE"
$PN"1"26;
"Y"
$PN"4"24;
"A"
$PN"2"27;
%"P3V3_STBY"
"1","(-550,2100)","0","mstr_symbols","I131";
;
HDL_POWER"P3V3_STBY"
BODY_TYPE"PLUMBING"
VOLTAGE"3.3V"
CDS_LIB"mstr_symbols"
SIZE"1B";
"G\NAC"5;
%"RES"
"2","(-550,1900)","0","mstr_discrete","I133";
;
CDS_SEC"1"
WATTAGE"1/16W"
PART_NUMBER"G21796-072"
VALUE"4.75K"
TOLERANCE"1%"
PACK_TYPE"0402"
MATERIAL"CHIP"
LOCATION"R8E14"
ROOM"SB"
CDS_LOCATION"R8E14"
SEC"1"
SEC_TYPE"0402"
CDS_LIB"mstr_discrete";
"A"
$PN"1"5;
"B"
$PN"2"26;
%"FET_N"
"8","(-550,1375)","0","mstr_discrete","I134";
;
CDS_SEC"1"
LOCATION"Q8E1"
PART_NUMBER"C79254-001"
VALUE"2N7002"
MATERIAL"FET"
PACK_TYPE"SOT23LF"
ROOM"SB"
CDS_LOCATION"Q8E1"
SEC"1"
SEC_TYPE"SOT23LF"
CDS_LIB"mstr_discrete";
"GATE"
$PN"1"11;
"DRN"
$PN"3"26;
"SRC"
$PN"2"6;
%"GND"
"1","(-550,1075)","0","mstr_symbols","I135";
;
HDL_POWER"GND"
BODY_TYPE"PLUMBING"
VOLTAGE"0.0V"
CDS_LIB"mstr_symbols"
SIZE"1B";
"A\NAC"6;
%"RES"
"2","(-400,4800)","0","mstr_discrete","I139";
;
CDS_SEC"1"
CDS_LOCATION"R7G31"
LOCATION"R7G31"
VALUE"1.00K"
TOLERANCE"1%"
PACK_TYPE"0402"
WATTAGE"1/16W"
MATERIAL"CHIP"
PART_NUMBER"G21796-026"
ROOM"SB"
CDS_LIB"mstr_discrete"
BOM_COST"SB"
SEC_TYPE"0402"
SEC"1";
"A"
$PN"1"9;
"B"
$PN"2"13;
%"RES"
"2","(0,3900)","0","mstr_discrete","I140";
;
CDS_SEC"1"
VALUE"20.0K"
TOLERANCE"1%"
PART_NUMBER"G21796-040"
PACK_TYPE"0402"
MATERIAL"CHIP"
WATTAGE"1/16W"
LOCATION"R8E16"
ROOM"SB"
CDS_LOCATION"R8E16"
BOM_COST"SB"
CDS_LIB"mstr_discrete"
SEC_TYPE"0402"
SEC"1";
"A"
$PN"1"14;
"B"
$PN"2"7;
%"GND"
"1","(0,3700)","0","mstr_symbols","I141";
;
HDL_POWER"GND"
BODY_TYPE"PLUMBING"
VOLTAGE"0"
ROOM"WBG_HEADERS_BIOS"
CDS_LIB"mstr_symbols"
SIZE"1B"
BOM_COST"SB";
"A\NAC"7;
%"RES"
"2","(-2500,4800)","2","mstr_discrete","I147";
;
CDS_SEC"1"
CDS_LOCATION"R2N28"
MATERIAL"CHIP"
VALUE"10.0K"
PART_NUMBER"G21796-016"
LOCATION"R2N28"
WATTAGE"1/16W"
TOLERANCE"1%"
PACK_TYPE"0402"
SEC"1"
SEC_TYPE"0402"
BOM_COST"SB"
CDS_LIB"mstr_discrete"
ROOM"SB";
"A"
$PN"1"2;
"B"
$PN"2"18;
%"RES"
"2","(-3100,3850)","0","mstr_discrete","I148";
;
CDS_SEC"1"
CDS_LOCATION"R7G29"
MATERIAL"CHIP"
PACK_TYPE"0402"
WATTAGE"1/16W"
TOLERANCE"1%"
VALUE"1.00K"
PART_NUMBER"G21796-026"
LOCATION"R7G29"
ROOM"SB"
CDS_LIB"mstr_discrete"
BOM_COST"SB"
SEC_TYPE"0402"
SEC"1";
"A"
$PN"1"22;
"B"
$PN"2"8;
%"GND"
"1","(-3100,3650)","0","mstr_symbols","I152";
;
HDL_POWER"GND"
BODY_TYPE"PLUMBING"
VOLTAGE"0"
ROOM"WBG_HEADERS_BIOS"
BOM_COST"SB"
CDS_LIB"mstr_symbols"
SIZE"1B";
"A\NAC"8;
%"P3V3_STBY"
"1","(-600,5025)","0","mstr_symbols","I154";
;
HDL_POWER"P3V3_STBY"
BODY_TYPE"PLUMBING"
CDS_LIB"mstr_symbols"
SIZE"1B"
VOLTAGE"3.3V";
"G\NAC"9;
%"RES"
"2","(-600,4800)","2","mstr_discrete","I155";
;
CDS_SEC"1"
CDS_LOCATION"R7G27"
WATTAGE"1/16W"
PACK_TYPE"0402"
PART_NUMBER"G21796-026"
MATERIAL"CHIP"
TOLERANCE"1%"
VALUE"1.00K"
LOCATION"R7G27"
SEC"1"
CDS_LIB"mstr_discrete"
BOM_COST"SB"
SEC_TYPE"0402"
ROOM"SB";
"A"
$PN"1"9;
"B"
$PN"2"12;
%"RES"
"2","(-300,3900)","0","mstr_discrete","I156";
;
CDS_SEC"1"
CDS_LOCATION"R3T14"
LOCATION"R3T14"
VALUE"10.0K"
TOLERANCE"1%"
PART_NUMBER"G21796-016"
PACK_TYPE"0402"
WATTAGE"1/16W"
MATERIAL"CHIP"
ROOM"SB"
SEC_TYPE"0402"
CDS_LIB"mstr_discrete"
BOM_COST"SB"
SEC"1";
"A"
$PN"1"15;
"B"
$PN"2"10;
%"GND"
"1","(-300,3700)","0","mstr_symbols","I157";
;
HDL_POWER"GND"
BODY_TYPE"PLUMBING"
VOLTAGE"0"
SIZE"1B"
BOM_COST"SB"
CDS_LIB"mstr_symbols";
"A\NAC"10;
%"CONN12_C73564003"
"1","(-1650,4250)","0","mstr_conn","I174";
;
CDS_SEC"1"
CDS_LOCATION"J7G3"
LOCATION"J7G3"
PART_NUMBER"C73564-003"
MATERIAL"CONN"
PACK_TYPE"PIP"
ROOM"SB"
SEC_TYPE"PIP"
SEC"1"
CDS_LIB"mstr_conn"
BOM_COST"SB";
"IO9"
$PN"9"18;
"IO11"
$PN"11"22;
"IO7"
$PN"7"20;
"IO3"
$PN"3"23;
"IO1"
$PN"1"19;
"IO5"
$PN"5"21;
"IO8"
$PN"8"16;
"IO10"
$PN"10"14;
"IO12"
$PN"12"13;
"IO6"
$PN"6"12;
"IO4"
$PN"4"15;
"IO2"
$PN"2"17;
END.
